# T6G (Grand Teton) — schematic netlist excerpt (pin names and nets, part order shuffled) for the footprints in the layout excerpt that follows; sources: Cadence DE-HDL packaged netlist, KiCad conversion of 04192023_DAF0TMB3IC0_F0TG_MB_C_brd_V02_OCP.brd

R1248  Q_RES  0 5% EMPTY  pkg 0402LF  page 258 : A = PVDD_33_S5_ADC ; B = PVDD_33_S5_ADC_MAM
C276  Q_CAP  22UF 4V 20% X6S  pkg C0402  page 69 : A = PVDDCR_CPU0_P0 ; B = GND
C7019  Q_CAP  100UF 4V 20% X6S  pkg C0805  page 312 : A = P0V9_CPU0_RT3_2A ; B = GND

(kicad_pcb
	(version 20260206)
	(generator "pcbnew")
	(generator_version "10.0")
	(general
		(thickness 1.6)
		(legacy_teardrops no)
	)
	(paper "A4")
	(title_block
		(title "04192023_DAF0TMB3IC0_F0TG_MB_C_brd_V02_OCP.brd")
		(comment 1 "Grand Teton / footprints 7059-7061 of 8354")
	)
	(layers
		(0 "F.Cu" signal "TOP")
		(4 "In1.Cu" signal "GND")
		(6 "In2.Cu" signal "IN1")
		(8 "In3.Cu" signal "GND1")
		(10 "In4.Cu" signal "IN2")
		(12 "In5.Cu" signal "GND2")
		(14 "In6.Cu" signal "IN3")
		(16 "In7.Cu" signal "GND3")
		(18 "In8.Cu" signal "VCC")
		(20 "In9.Cu" signal "VCC1")
		(22 "In10.Cu" signal "GND4")
		(24 "In11.Cu" signal "IN4")
		(26 "In12.Cu" signal "GND5")
		(28 "In13.Cu" signal "IN5")
		(30 "In14.Cu" signal "GND6")
		(32 "In15.Cu" signal "IN6")
		(34 "In16.Cu" signal "GND7")
		(2 "B.Cu" signal "BOTTOM")
		(9 "F.Adhes" user "F.Adhesive")
		(11 "B.Adhes" user "B.Adhesive")
		(13 "F.Paste" user "Package Geometry/Pastemask Top")
		(15 "B.Paste" user "Package Geometry/Pastemask Bottom")
		(5 "F.SilkS" user "Ref Des/Silkscreen Top")
		(7 "B.SilkS" user "Ref Des/Silkscreen Bottom")
		(1 "F.Mask" user "Board Geometry/Soldermask Top")
		(3 "B.Mask" user "Board Geometry/Soldermask Bottom")
		(17 "Dwgs.User" user "User.Drawings")
		(19 "Cmts.User" user "User.Comments")
		(21 "Eco1.User" user "User.Eco1")
		(23 "Eco2.User" user "User.Eco2")
		(25 "Edge.Cuts" user "Board Geometry/Outline")
		(27 "Margin" user)
		(31 "F.CrtYd" user "Package Geometry/Place Bound Top")
		(29 "B.CrtYd" user "Package Geometry/Place Bound Bottom")
		(35 "F.Fab" user "Ref Des/Assembly Top")
		(33 "B.Fab" user "Ref Des/Assembly Bottom")
	)
	(footprint ""
		(layer "B.Cu")
		(at 231.8512 -327.21169 180)
		(property "Reference" "R1248"
			(at 0 0 0)
			(layer "B.SilkS")
			(hide yes)
			(effects
				(font
					(size 1.27 1.27)
				)
				(justify mirror)
			)
		)
		(property "Value" ""
			(at 0 0 0)
			(layer "B.Fab")
			(effects
				(font
					(size 1.27 1.27)
				)
				(justify mirror)
			)
		)
		(duplicate_pad_numbers_are_jumpers no)
		(fp_line
			(start 0.7874 0.4064)
			(end 0.7874 -0.4064)
			(stroke
				(width 0.1524)
				(type default)
			)
			(layer "B.SilkS")
		)
		(fp_line
			(start 0.7874 -0.4064)
			(end -0.7874 -0.4064)
			(stroke
				(width 0.1524)
				(type default)
			)
			(layer "B.SilkS")
		)
		(fp_line
			(start -0.7874 0.4064)
			(end 0.7874 0.4064)
			(stroke
				(width 0.1524)
				(type default)
			)
			(layer "B.SilkS")
		)
		(fp_line
			(start -0.7874 -0.4064)
			(end -0.7874 0.4064)
			(stroke
				(width 0.1524)
				(type default)
			)
			(layer "B.SilkS")
		)
		(fp_line
			(start 0.67945 0.3048)
			(end 0.67945 -0.305054)
			(stroke
				(width 0.1)
				(type default)
			)
			(layer "B.Fab")
		)
		(fp_line
			(start 0.67945 -0.305054)
			(end 0.12065 -0.305054)
			(stroke
				(width 0.1)
				(type default)
			)
			(layer "B.Fab")
		)
		(fp_line
			(start 0.12065 0.3048)
			(end 0.67945 0.3048)
			(stroke
				(width 0.1)
				(type default)
			)
			(layer "B.Fab")
		)
		(fp_line
			(start 0.12065 0.2794)
			(end 0.12065 0.3048)
			(stroke
				(width 0.1)
				(type default)
			)
			(layer "B.Fab")
		)
		(fp_line
			(start 0.12065 -0.2794)
			(end -0.12065 -0.2794)
			(stroke
				(width 0.1)
				(type default)
			)
			(layer "B.Fab")
		)
		(fp_line
			(start 0.12065 -0.305054)
			(end 0.12065 -0.2794)
			(stroke
				(width 0.1)
				(type default)
			)
			(layer "B.Fab")
		)
		(fp_line
			(start -0.120396 0.3048)
			(end -0.120396 0.2794)
			(stroke
				(width 0.1)
				(type default)
			)
			(layer "B.Fab")
		)
		(fp_line
			(start -0.120396 0.2794)
			(end 0.12065 0.2794)
			(stroke
				(width 0.1)
				(type default)
			)
			(layer "B.Fab")
		)
		(fp_line
			(start -0.12065 -0.2794)
			(end -0.12065 -0.3048)
			(stroke
				(width 0.1)
				(type default)
			)
			(layer "B.Fab")
		)
		(fp_line
			(start -0.12065 -0.3048)
			(end -0.67945 -0.3048)
			(stroke
				(width 0.1)
				(type default)
			)
			(layer "B.Fab")
		)
		(fp_line
			(start -0.67945 0.3048)
			(end -0.120396 0.3048)
			(stroke
				(width 0.1)
				(type default)
			)
			(layer "B.Fab")
		)
		(fp_line
			(start -0.67945 -0.3048)
			(end -0.67945 0.3048)
			(stroke
				(width 0.1)
				(type default)
			)
			(layer "B.Fab")
		)
		(pad "1" smd rect
			(at 0.40005 0 180)
			(size 0.4572 0.508)
			(layers "B.Cu" "B.Mask" "B.Paste")
			(net "PVDD_33_S5_ADC")
		)
		(pad "2" smd rect
			(at -0.40005 0 180)
			(size 0.4572 0.508)
			(layers "B.Cu" "B.Mask" "B.Paste")
			(net "PVDD_33_S5_ADC_MAM")
		)
	)
	(footprint ""
		(layer "B.Cu")
		(at 368.701828 -390.078722)
		(property "Reference" "C7019"
			(at 0 0 0)
			(layer "B.SilkS")
			(hide yes)
			(effects
				(font
					(size 1.27 1.27)
				)
				(justify mirror)
			)
		)
		(property "Value" ""
			(at 0 0 0)
			(layer "B.Fab")
			(effects
				(font
					(size 1.27 1.27)
				)
				(justify mirror)
			)
		)
		(duplicate_pad_numbers_are_jumpers no)
		(fp_line
			(start -1.524 -0.762)
			(end -1.524 0.762)
			(stroke
				(width 0.1524)
				(type default)
			)
			(layer "B.SilkS")
		)
		(fp_line
			(start -1.524 0.762)
			(end 1.524 0.762)
			(stroke
				(width 0.1524)
				(type default)
			)
			(layer "B.SilkS")
		)
		(fp_line
			(start 1.524 -0.762)
			(end -1.524 -0.762)
			(stroke
				(width 0.1524)
				(type default)
			)
			(layer "B.SilkS")
		)
		(fp_line
			(start 1.524 0.762)
			(end 1.524 -0.762)
			(stroke
				(width 0.1524)
				(type default)
			)
			(layer "B.SilkS")
		)
		(fp_line
			(start -1.1049 -0.724916)
			(end 1.1049 -0.724916)
			(stroke
				(width 0.1)
				(type default)
			)
			(layer "B.Fab")
		)
		(fp_line
			(start -1.1049 0.724916)
			(end -1.1049 -0.724916)
			(stroke
				(width 0.1)
				(type default)
			)
			(layer "B.Fab")
		)
		(fp_line
			(start 1.1049 -0.724916)
			(end 1.1049 0.724916)
			(stroke
				(width 0.1)
				(type default)
			)
			(layer "B.Fab")
		)
		(fp_line
			(start 1.1049 0.724916)
			(end -1.1049 0.724916)
			(stroke
				(width 0.1)
				(type default)
			)
			(layer "B.Fab")
		)
		(pad "1" smd rect
			(at 0.889 0)
			(size 1.016 1.27)
			(layers "B.Cu" "B.Mask" "B.Paste")
			(net "P0V9_CPU0_RT3_2A")
		)
		(pad "2" smd rect
			(at -0.889 0)
			(size 1.016 1.27)
			(layers "B.Cu" "B.Mask" "B.Paste")
			(net "GND")
		)
	)
	(footprint ""
		(layer "B.Cu")
		(at 350.818958 -250.89231 180)
		(property "Reference" "C276"
			(at 0 0 0)
			(layer "B.SilkS")
			(hide yes)
			(effects
				(font
					(size 1.27 1.27)
				)
				(justify mirror)
			)
		)
		(property "Value" ""
			(at 0 0 0)
			(layer "B.Fab")
			(effects
				(font
					(size 1.27 1.27)
				)
				(justify mirror)
			)
		)
		(duplicate_pad_numbers_are_jumpers no)
		(fp_line
			(start 0.7874 0.4064)
			(end 0.7874 -0.4064)
			(stroke
				(width 0.1524)
				(type default)
			)
			(layer "B.SilkS")
		)
		(fp_line
			(start 0.7874 -0.4064)
			(end -0.7874 -0.4064)
			(stroke
				(width 0.1524)
				(type default)
			)
			(layer "B.SilkS")
		)
		(fp_line
			(start -0.7874 0.4064)
			(end 0.7874 0.4064)
			(stroke
				(width 0.1524)
				(type default)
			)
			(layer "B.SilkS")
		)
		(fp_line
			(start -0.7874 -0.4064)
			(end -0.7874 0.4064)
			(stroke
				(width 0.1524)
				(type default)
			)
			(layer "B.SilkS")
		)
		(fp_line
			(start 0.67945 0.3048)
			(end 0.67945 -0.305054)
			(stroke
				(width 0.1)
				(type default)
			)
			(layer "B.Fab")
		)
		(fp_line
			(start 0.67945 -0.305054)
			(end 0.12065 -0.305054)
			(stroke
				(width 0.1)
				(type default)
			)
			(layer "B.Fab")
		)
		(fp_line
			(start 0.12065 0.3048)
			(end 0.67945 0.3048)
			(stroke
				(width 0.1)
				(type default)
			)
			(layer "B.Fab")
		)
		(fp_line
			(start 0.12065 0.2794)
			(end 0.12065 0.3048)
			(stroke
				(width 0.1)
				(type default)
			)
			(layer "B.Fab")
		)
		(fp_line
			(start 0.12065 -0.2794)
			(end -0.12065 -0.2794)
			(stroke
				(width 0.1)
				(type default)
			)
			(layer "B.Fab")
		)
		(fp_line
			(start 0.12065 -0.305054)
			(end 0.12065 -0.2794)
			(stroke
				(width 0.1)
				(type default)
			)
			(layer "B.Fab")
		)
		(fp_line
			(start -0.120396 0.3048)
			(end -0.120396 0.2794)
			(stroke
				(width 0.1)
				(type default)
			)
			(layer "B.Fab")
		)
		(fp_line
			(start -0.120396 0.2794)
			(end 0.12065 0.2794)
			(stroke
				(width 0.1)
				(type default)
			)
			(layer "B.Fab")
		)
		(fp_line
			(start -0.12065 -0.2794)
			(end -0.12065 -0.3048)
			(stroke
				(width 0.1)
				(type default)
			)
			(layer "B.Fab")
		)
		(fp_line
			(start -0.12065 -0.3048)
			(end -0.67945 -0.3048)
			(stroke
				(width 0.1)
				(type default)
			)
			(layer "B.Fab")
		)
		(fp_line
			(start -0.67945 0.3048)
			(end -0.120396 0.3048)
			(stroke
				(width 0.1)
				(type default)
			)
			(layer "B.Fab")
		)
		(fp_line
			(start -0.67945 -0.3048)
			(end -0.67945 0.3048)
			(stroke
				(width 0.1)
				(type default)
			)
			(layer "B.Fab")
		)
		(pad "1" smd circle
			(at 0.40005 0)
			(size 0 0)
			(layers "B.Cu" "B.Mask" "B.Paste")
			(net "PVDDCR_CPU0_P0")
		)
		(pad "2" smd circle
			(at -0.40005 0)
			(size 0 0)
			(layers "B.Cu" "B.Mask" "B.Paste")
			(net "GND")
		)
	)
)
